# T6G (Grand Teton) — schematic parts with pin connectivity, parts 8082–8082 of 8303; source: Cadence DE-HDL packaged netlist (pstxprt.dat, pstxnet.dat, pstchip.dat)

U26  GENOA_SP5  SOCKET6096_13568-001 IO  pkg SOCKET6096_93-4X120-45XA  page 37  (pins 3025-3360 of 6096)
  CD8  VSS_CD8  POWER  = GND
  CD9  MLB_DQS_H0  BI  = M_L_CPU1_SB_DQS_DP<0>
  CD10  VSS_CD10  POWER  = GND
  CD11  MLB_DATA3  BI  = M_L_CPU1_SB_DQ<3>
  CD12  VDD_11_S3_CD12  POWER  = PVDD11_S3_P1
  CD13  MHB_DQS_H0  BI  = M_H_CPU1_SB_DQS_DP<0>
  CD14  MHB_DATA3  BI  = M_H_CPU1_SB_DQ<3>
  CD15  VSS_CD15  POWER  = GND
  CD16  MJB_DQS_H0  BI  = M_J_CPU1_SB_DQS_DP<0>
  CD17  VSS_CD17  POWER  = GND
  CD18  MJB_DATA3  BI  = M_J_CPU1_SB_DQ<3>
  CD19  VDD_11_S3_CD19  POWER  = PVDD11_S3_P1
  CD20  MIB_DQS_H0  BI  = M_I_CPU1_SB_DQS_DP<0>
  CD21  MIB_DATA3  BI  = M_I_CPU1_SB_DQ<3>
  CD22  VSS_CD22  POWER  = GND
  CD23  VDDCR_CPU1_CD23  POWER  = PVDDCR_CPU1_P1
  CD24  VDDCR_CPU1_CD24  POWER  = PVDDCR_CPU1_P1
  CD25  VSS_CD25  POWER  = GND
  CD26  VDDCR_CPU1_CD26  POWER  = PVDDCR_CPU1_P1
  CD27  VDDCR_CPU1_CD27  POWER  = PVDDCR_CPU1_P1
  CD28  VSS_CD28  POWER  = GND
  CD29  VDDCR_CPU1_CD29  POWER  = PVDDCR_CPU1_P1
  CD30  VDDCR_CPU1_CD30  POWER  = PVDDCR_CPU1_P1
  CD31  VSS_CD31  POWER  = GND
  CD32  VDDCR_CPU1_CD32  POWER  = PVDDCR_CPU1_P1
  CD33  VDDCR_CPU1_CD33  POWER  = PVDDCR_CPU1_P1
  CD34  VSS_CD34  POWER  = GND
  CD35  P3_TXN0  OUT  = P5E_CPU1_P3_TX_DN<0>
  CD36  P3_TXP0  OUT  = P5E_CPU1_P3_TX_DP<0>
  CD37  VSS_CD37  POWER  = GND
  CD39  VSS_CD39  POWER  = GND
  CD40  P1_RXP15  IN  = P5E_CPU1_P1_RX_DP<15>
  CD41  P1_RXN15  IN  = P5E_CPU1_P1_RX_DN<15>
  CD42  VSS_CD42  POWER  = GND
  CD43  VDDCR_CPU1_CD43  POWER  = PVDDCR_CPU1_P1
  CD44  VDDCR_CPU1_CD44  POWER  = PVDDCR_CPU1_P1
  CD45  VSS_CD45  POWER  = GND
  CD46  VDDCR_CPU1_CD46  POWER  = PVDDCR_CPU1_P1
  CD47  VDDCR_CPU1_CD47  POWER  = PVDDCR_CPU1_P1
  CD48  VSS_CD48  POWER  = GND
  CD49  VDDCR_CPU1_CD49  POWER  = PVDDCR_CPU1_P1
  CD50  VDDCR_CPU1_CD50  POWER  = PVDDCR_CPU1_P1
  CD51  VSS_CD51  POWER  = GND
  CD52  VDDCR_CPU1_CD52  POWER  = PVDDCR_CPU1_P1
  CD53  VDDCR_CPU1_CD53  POWER  = PVDDCR_CPU1_P1
  CD54  VSS_CD54  POWER  = GND
  CD55  MCB_DATA3  BI  = M_C_CPU1_SB_DQ<3>
  CD56  MCB_DQS_H0  BI  = M_C_CPU1_SB_DQS_DP<0>
  CD57  VDDIO_CD57  POWER  = PVDDIO_P1
  CD58  MDB_DATA3  BI  = M_D_CPU1_SB_DQ<3>
  CD59  VSS_CD59  POWER  = GND
  CD60  MDB_DQS_H0  BI  = M_D_CPU1_SB_DQS_DP<0>
  CD61  VSS_CD61  POWER  = GND
  CD62  MBB_DATA3  BI  = M_B_CPU1_SB_DQ<3>
  CD63  MBB_DQS_H0  BI  = M_B_CPU1_SB_DQS_DP<0>
  CD64  VDDIO_CD64  POWER  = PVDDIO_P1
  CD65  MFB_DATA3  BI  = M_F_CPU1_SB_DQ<3>
  CD66  VSS_CD66  POWER  = GND
  CD67  MFB_DQS_H0  BI  = M_F_CPU1_SB_DQS_DP<0>
  CD68  VSS_CD68  POWER  = GND
  CD69  MEB_DATA3  BI  = M_E_CPU1_SB_DQ<3>
  CD70  MEB_DQS_H0  BI  = M_E_CPU1_SB_DQS_DP<0>
  CD71  VDDIO_CD71  POWER  = PVDDIO_P1
  CD72  MAB_DATA3  BI  = M_A_CPU1_SB_DQ<3>
  CD73  VSS_CD73  POWER  = GND
  CD74  MAB_DQS_H0  BI  = M_A_CPU1_SB_DQS_DP<0>
  CE1  VSS_CE1  POWER  = GND
  CE2  MGB_DQS_L0  BI  = M_G_CPU1_SB_DQS_DN<0>
  CE3  MGB_DQS_L5  BI  = M_G_CPU1_SB_DQS_DN<5>
  CE4  VSS_CE4  POWER  = GND
  CE5  MKB_DQS_L0  BI  = M_K_CPU1_SB_DQS_DN<0>
  CE6  VSS_CE6  POWER  = GND
  CE7  MKB_DQS_L5  BI  = M_K_CPU1_SB_DQS_DN<5>
  CE8  VSS_CE8  POWER  = GND
  CE9  MLB_DQS_L0  BI  = M_L_CPU1_SB_DQS_DN<0>
  CE10  MLB_DQS_L5  BI  = M_L_CPU1_SB_DQS_DN<5>
  CE11  VSS_CE11  POWER  = GND
  CE12  MHB_DQS_L0  BI  = M_H_CPU1_SB_DQS_DN<0>
  CE13  VSS_CE13  POWER  = GND
  CE14  MHB_DQS_L5  BI  = M_H_CPU1_SB_DQS_DN<5>
  CE15  VSS_CE15  POWER  = GND
  CE16  MJB_DQS_L0  BI  = M_J_CPU1_SB_DQS_DN<0>
  CE17  MJB_DQS_L5  BI  = M_J_CPU1_SB_DQS_DN<5>
  CE18  VSS_CE18  POWER  = GND
  CE19  MIB_DQS_L0  BI  = M_I_CPU1_SB_DQS_DN<0>
  CE20  VSS_CE20  POWER  = GND
  CE21  MIB_DQS_L5  BI  = M_I_CPU1_SB_DQS_DN<5>
  CE22  VSS_CE22  POWER  = GND
  CE23  P3_TXN15  OUT  = P5E_CPU1_P3_TX_DN<15>
  CE24  P3_TXP15  OUT  = P5E_CPU1_P3_TX_DP<15>
  CE25  VSS_CE25  POWER  = GND
  CE26  P3_TXN12  OUT  = P5E_CPU1_P3_TX_DN<12>
  CE27  P3_TXP12  OUT  = P5E_CPU1_P3_TX_DP<12>
  CE28  VSS_CE28  POWER  = GND
  CE29  P3_TXN9  OUT  = P5E_CPU1_P3_TX_DN<9>
  CE30  P3_TXP9  OUT  = P5E_CPU1_P3_TX_DP<9>
  CE31  VSS_CE31  POWER  = GND
  CE32  P3_TXN6  OUT  = P5E_CPU1_P3_TX_DN<6>
  CE33  P3_TXP6  OUT  = P5E_CPU1_P3_TX_DP<6>
  CE34  VSS_CE34  POWER  = GND
  CE35  VSS_CE35  POWER  = GND
  CE36  VSS_CE36  POWER  = GND
  CE40  VSS_CE40  POWER  = GND
  CE41  VSS_CE41  POWER  = GND
  CE42  VSS_CE42  POWER  = GND
  CE43  P1_RXP9  IN  = P5E_CPU1_P1_RX_DP<9>
  CE44  P1_RXN9  IN  = P5E_CPU1_P1_RX_DN<9>
  CE45  VSS_CE45  POWER  = GND
  CE46  P1_RXP6  IN  = P5E_CPU1_P1_RX_DP<6>
  CE47  P1_RXN6  IN  = P5E_CPU1_P1_RX_DN<6>
  CE48  VSS_CE48  POWER  = GND
  CE49  P1_RXP3  IN  = P5E_CPU1_P1_RX_DP<3>
  CE50  P1_RXN3  IN  = P5E_CPU1_P1_RX_DN<3>
  CE51  VSS_CE51  POWER  = GND
  CE52  P1_RXP0  IN  = P5E_CPU1_P1_RX_DP<0>
  CE53  P1_RXN0  IN  = P5E_CPU1_P1_RX_DN<0>
  CE54  VSS_CE54  POWER  = GND
  CE55  MCB_DQS_L5  BI  = M_C_CPU1_SB_DQS_DN<5>
  CE56  VSS_CE56  POWER  = GND
  CE57  MCB_DQS_L0  BI  = M_C_CPU1_SB_DQS_DN<0>
  CE58  VSS_CE58  POWER  = GND
  CE59  MDB_DQS_L5  BI  = M_D_CPU1_SB_DQS_DN<5>
  CE60  MDB_DQS_L0  BI  = M_D_CPU1_SB_DQS_DN<0>
  CE61  VSS_CE61  POWER  = GND
  CE62  MBB_DQS_L5  BI  = M_B_CPU1_SB_DQS_DN<5>
  CE63  VSS_CE63  POWER  = GND
  CE64  MBB_DQS_L0  BI  = M_B_CPU1_SB_DQS_DN<0>
  CE65  VSS_CE65  POWER  = GND
  CE66  MFB_DQS_L5  BI  = M_F_CPU1_SB_DQS_DN<5>
  CE67  MFB_DQS_L0  BI  = M_F_CPU1_SB_DQS_DN<0>
  CE68  VSS_CE68  POWER  = GND
  CE69  MEB_DQS_L5  BI  = M_E_CPU1_SB_DQS_DN<5>
  CE70  VSS_CE70  POWER  = GND
  CE71  MEB_DQS_L0  BI  = M_E_CPU1_SB_DQS_DN<0>
  CE72  VSS_CE72  POWER  = GND
  CE73  MAB_DQS_L5  BI  = M_A_CPU1_SB_DQS_DN<5>
  CE74  MAB_DQS_L0  BI  = M_A_CPU1_SB_DQS_DN<0>
  CE75  VSS_CE75  POWER  = GND
  CF2  MGB_DATA4  BI  = M_G_CPU1_SB_DQ<4>
  CF3  VSS_CF3  POWER  = GND
  CF4  MGB_DQS_H5  BI  = M_G_CPU1_SB_DQS_DP<5>
  CF5  VSS_CF5  POWER  = GND
  CF6  MKB_DATA4  BI  = M_K_CPU1_SB_DQ<4>
  CF7  MKB_DQS_H5  BI  = M_K_CPU1_SB_DQS_DP<5>
  CF8  VSS_CF8  POWER  = GND
  CF9  MLB_DATA4  BI  = M_L_CPU1_SB_DQ<4>
  CF10  VSS_CF10  POWER  = GND
  CF11  MLB_DQS_H5  BI  = M_L_CPU1_SB_DQS_DP<5>
  CF12  VSS_CF12  POWER  = GND
  CF13  MHB_DATA4  BI  = M_H_CPU1_SB_DQ<4>
  CF14  MHB_DQS_H5  BI  = M_H_CPU1_SB_DQS_DP<5>
  CF15  VSS_CF15  POWER  = GND
  CF16  MJB_DATA4  BI  = M_J_CPU1_SB_DQ<4>
  CF17  VSS_CF17  POWER  = GND
  CF18  MJB_DQS_H5  BI  = M_J_CPU1_SB_DQS_DP<5>
  CF19  VSS_CF19  POWER  = GND
  CF20  MIB_DATA4  BI  = M_I_CPU1_SB_DQ<4>
  CF21  MIB_DQS_H5  BI  = M_I_CPU1_SB_DQS_DP<5>
  CF22  VDD_11_S3_CF22  POWER  = PVDD11_S3_P1
  CF23  VSS_CF23  POWER  = GND
  CF24  VSS_CF24  POWER  = GND
  CF25  VSS_CF25  POWER  = GND
  CF26  VSS_CF26  POWER  = GND
  CF27  VSS_CF27  POWER  = GND
  CF28  VSS_CF28  POWER  = GND
  CF29  VSS_CF29  POWER  = GND
  CF30  VSS_CF30  POWER  = GND
  CF31  VSS_CF31  POWER  = GND
  CF32  VSS_CF32  POWER  = GND
  CF33  VSS_CF33  POWER  = GND
  CF34  VSS_CF34  POWER  = GND
  CF35  P3_TXN1  OUT  = P5E_CPU1_P3_TX_DN<1>
  CF36  P3_TXP1  OUT  = P5E_CPU1_P3_TX_DP<1>
  CF37  VSS_CF37  POWER  = GND
  CF39  VSS_CF39  POWER  = GND
  CF40  P1_RXP14  IN  = P5E_CPU1_P1_RX_DP<14>
  CF41  P1_RXN14  IN  = P5E_CPU1_P1_RX_DN<14>
  CF42  VSS_CF42  POWER  = GND
  CF43  VSS_CF43  POWER  = GND
  CF44  VSS_CF44  POWER  = GND
  CF45  VSS_CF45  POWER  = GND
  CF46  VSS_CF46  POWER  = GND
  CF47  VSS_CF47  POWER  = GND
  CF48  VSS_CF48  POWER  = GND
  CF49  VSS_CF49  POWER  = GND
  CF50  VSS_CF50  POWER  = GND
  CF51  VSS_CF51  POWER  = GND
  CF52  VSS_CF52  POWER  = GND
  CF53  VSS_CF53  POWER  = GND
  CF54  VDDIO_CF54  POWER  = PVDDIO_P1
  CF55  MCB_DQS_H5  BI  = M_C_CPU1_SB_DQS_DP<5>
  CF56  MCB_DATA4  BI  = M_C_CPU1_SB_DQ<4>
  CF57  VSS_CF57  POWER  = GND
  CF58  MDB_DQS_H5  BI  = M_D_CPU1_SB_DQS_DP<5>
  CF59  VSS_CF59  POWER  = GND
  CF60  MDB_DATA4  BI  = M_D_CPU1_SB_DQ<4>
  CF61  VSS_CF61  POWER  = GND
  CF62  MBB_DQS_H5  BI  = M_B_CPU1_SB_DQS_DP<5>
  CF63  MBB_DATA4  BI  = M_B_CPU1_SB_DQ<4>
  CF64  VSS_CF64  POWER  = GND
  CF65  MFB_DQS_H5  BI  = M_F_CPU1_SB_DQS_DP<5>
  CF66  VSS_CF66  POWER  = GND
  CF67  MFB_DATA4  BI  = M_F_CPU1_SB_DQ<4>
  CF68  VSS_CF68  POWER  = GND
  CF69  MEB_DQS_H5  BI  = M_E_CPU1_SB_DQS_DP<5>
  CF70  MEB_DATA4  BI  = M_E_CPU1_SB_DQ<4>
  CF71  VSS_CF71  POWER  = GND
  CF72  MAB_DQS_H5  BI  = M_A_CPU1_SB_DQS_DP<5>
  CF73  VSS_CF73  POWER  = GND
  CF74  MAB_DATA4  BI  = M_A_CPU1_SB_DQ<4>
  CG1  VSS_CG1  POWER  = GND
  CG2  MGB_DATA6  BI  = M_G_CPU1_SB_DQ<6>
  CG3  MGB_DATA5  BI  = M_G_CPU1_SB_DQ<5>
  CG4  VDD_11_S3_CG4  POWER  = PVDD11_S3_P1
  CG5  MKB_DATA6  BI  = M_K_CPU1_SB_DQ<6>
  CG6  VSS_CG6  POWER  = GND
  CG7  MKB_DATA5  BI  = M_K_CPU1_SB_DQ<5>
  CG8  VSS_CG8  POWER  = GND
  CG9  MLB_DATA6  BI  = M_L_CPU1_SB_DQ<6>
  CG10  MLB_DATA5  BI  = M_L_CPU1_SB_DQ<5>
  CG11  VDD_11_S3_CG11  POWER  = PVDD11_S3_P1
  CG12  MHB_DATA6  BI  = M_H_CPU1_SB_DQ<6>
  CG13  VSS_CG13  POWER  = GND
  CG14  MHB_DATA5  BI  = M_H_CPU1_SB_DQ<5>
  CG15  VSS_CG15  POWER  = GND
  CG16  MJB_DATA6  BI  = M_J_CPU1_SB_DQ<6>
  CG17  MJB_DATA5  BI  = M_J_CPU1_SB_DQ<5>
  CG18  VDD_11_S3_CG18  POWER  = PVDD11_S3_P1
  CG19  MIB_DATA6  BI  = M_I_CPU1_SB_DQ<6>
  CG20  VSS_CG20  POWER  = GND
  CG21  MIB_DATA5  BI  = M_I_CPU1_SB_DQ<5>
  CG22  VSS_CG22  POWER  = GND
  CG23  P3_TXN14  OUT  = P5E_CPU1_P3_TX_DN<14>
  CG24  P3_TXP14  OUT  = P5E_CPU1_P3_TX_DP<14>
  CG25  VSS_CG25  POWER  = GND
  CG26  P3_TXN11  OUT  = P5E_CPU1_P3_TX_DN<11>
  CG27  P3_TXP11  OUT  = P5E_CPU1_P3_TX_DP<11>
  CG28  VSS_CG28  POWER  = GND
  CG29  P3_TXN8  OUT  = P5E_CPU1_P3_TX_DN<8>
  CG30  P3_TXP8  OUT  = P5E_CPU1_P3_TX_DP<8>
  CG31  VSS_CG31  POWER  = GND
  CG32  P3_TXN5  OUT  = P5E_CPU1_P3_TX_DN<5>
  CG33  P3_TXP5  OUT  = P5E_CPU1_P3_TX_DP<5>
  CG34  VSS_CG34  POWER  = GND
  CG35  VDDCR_CPU1_CG35  POWER  = PVDDCR_CPU1_P1
  CG36  VDDCR_CPU1_CG36  POWER  = PVDDCR_CPU1_P1
  CG40  VDDCR_CPU1_CG40  POWER  = PVDDCR_CPU1_P1
  CG41  VDDCR_CPU1_CG41  POWER  = PVDDCR_CPU1_P1
  CG42  VSS_CG42  POWER  = GND
  CG43  P1_RXP10  IN  = P5E_CPU1_P1_RX_DP<10>
  CG44  P1_RXN10  IN  = P5E_CPU1_P1_RX_DN<10>
  CG45  VSS_CG45  POWER  = GND
  CG46  P1_RXP7  IN  = P5E_CPU1_P1_RX_DP<7>
  CG47  P1_RXN7  IN  = P5E_CPU1_P1_RX_DN<7>
  CG48  VSS_CG48  POWER  = GND
  CG49  P1_RXP4  IN  = P5E_CPU1_P1_RX_DP<4>
  CG50  P1_RXN4  IN  = P5E_CPU1_P1_RX_DN<4>
  CG51  VSS_CG51  POWER  = GND
  CG52  P1_RXP1  IN  = P5E_CPU1_P1_RX_DP<1>
  CG53  P1_RXN1  IN  = P5E_CPU1_P1_RX_DN<1>
  CG54  VSS_CG54  POWER  = GND
  CG55  MCB_DATA5  BI  = M_C_CPU1_SB_DQ<5>
  CG56  VSS_CG56  POWER  = GND
  CG57  MCB_DATA6  BI  = M_C_CPU1_SB_DQ<6>
  CG58  VDDIO_CG58  POWER  = PVDDIO_P1
  CG59  MDB_DATA5  BI  = M_D_CPU1_SB_DQ<5>
  CG60  MDB_DATA6  BI  = M_D_CPU1_SB_DQ<6>
  CG61  VSS_CG61  POWER  = GND
  CG62  MBB_DATA5  BI  = M_B_CPU1_SB_DQ<5>
  CG63  VSS_CG63  POWER  = GND
  CG64  MBB_DATA6  BI  = M_B_CPU1_SB_DQ<6>
  CG65  VDDIO_CG65  POWER  = PVDDIO_P1
  CG66  MFB_DATA5  BI  = M_F_CPU1_SB_DQ<5>
  CG67  MFB_DATA6  BI  = M_F_CPU1_SB_DQ<6>
  CG68  VSS_CG68  POWER  = GND
  CG69  MEB_DATA5  BI  = M_E_CPU1_SB_DQ<5>
  CG70  VSS_CG70  POWER  = GND
  CG71  MEB_DATA6  BI  = M_E_CPU1_SB_DQ<6>
  CG72  VDDIO_CG72  POWER  = PVDDIO_P1
  CG73  MAB_DATA5  BI  = M_A_CPU1_SB_DQ<5>
  CG74  MAB_DATA6  BI  = M_A_CPU1_SB_DQ<6>
  CG75  VSS_CG75  POWER  = GND
  CH2  MGB_DATA8  BI  = M_G_CPU1_SB_DQ<8>
  CH3  VSS_CH3  POWER  = GND
  CH4  MGB_DATA7  BI  = M_G_CPU1_SB_DQ<7>
  CH5  VSS_CH5  POWER  = GND
  CH6  MKB_DATA8  BI  = M_K_CPU1_SB_DQ<8>
  CH7  MKB_DATA7  BI  = M_K_CPU1_SB_DQ<7>
  CH8  VSS_CH8  POWER  = GND
  CH9  MLB_DATA8  BI  = M_L_CPU1_SB_DQ<8>
  CH10  VSS_CH10  POWER  = GND
  CH11  MLB_DATA7  BI  = M_L_CPU1_SB_DQ<7>
  CH12  VSS_CH12  POWER  = GND
  CH13  MHB_DATA8  BI  = M_H_CPU1_SB_DQ<8>
  CH14  MHB_DATA7  BI  = M_H_CPU1_SB_DQ<7>
  CH15  VSS_CH15  POWER  = GND
  CH16  MJB_DATA8  BI  = M_J_CPU1_SB_DQ<8>
  CH17  VSS_CH17  POWER  = GND
  CH18  MJB_DATA7  BI  = M_J_CPU1_SB_DQ<7>
  CH19  VSS_CH19  POWER  = GND
  CH20  MIB_DATA8  BI  = M_I_CPU1_SB_DQ<8>
  CH21  MIB_DATA7  BI  = M_I_CPU1_SB_DQ<7>
  CH22  VSS_CH22  POWER  = GND
  CH23  VDDCR_CPU1_CH23  POWER  = PVDDCR_CPU1_P1
  CH24  VDDCR_CPU1_CH24  POWER  = PVDDCR_CPU1_P1
  CH25  VSS_CH25  POWER  = GND
  CH26  VDDCR_CPU1_CH26  POWER  = PVDDCR_CPU1_P1
  CH27  VDDCR_CPU1_CH27  POWER  = PVDDCR_CPU1_P1
  CH28  VSS_CH28  POWER  = GND
  CH29  VDDCR_CPU1_CH29  POWER  = PVDDCR_CPU1_P1
  CH30  VDDCR_CPU1_CH30  POWER  = PVDDCR_CPU1_P1
  CH31  VSS_CH31  POWER  = GND
  CH32  VDDCR_CPU1_CH32  POWER  = PVDDCR_CPU1_P1
  CH33  VDDCR_CPU1_CH33  POWER  = PVDDCR_CPU1_P1
  CH34  VSS_CH34  POWER  = GND
  CH35  P3_TXN2  OUT  = P5E_CPU1_P3_TX_DN<2>
  CH36  P3_TXP2  OUT  = P5E_CPU1_P3_TX_DP<2>
  CH37  VSS_CH37  POWER  = GND
  CH39  VSS_CH39  POWER  = GND
  CH40  P1_RXP13  IN  = P5E_CPU1_P1_RX_DP<13>
  CH41  P1_RXN13  IN  = P5E_CPU1_P1_RX_DN<13>
  CH42  VSS_CH42  POWER  = GND
  CH43  VDDCR_CPU1_CH43  POWER  = PVDDCR_CPU1_P1
  CH44  VDDCR_CPU1_CH44  POWER  = PVDDCR_CPU1_P1
  CH45  VSS_CH45  POWER  = GND
  CH46  VDDCR_CPU1_CH46  POWER  = PVDDCR_CPU1_P1
  CH47  VDDCR_CPU1_CH47  POWER  = PVDDCR_CPU1_P1
  CH48  VSS_CH48  POWER  = GND
  CH49  VDDCR_CPU1_CH49  POWER  = PVDDCR_CPU1_P1
  CH50  VDDCR_CPU1_CH50  POWER  = PVDDCR_CPU1_P1
  CH51  VSS_CH51  POWER  = GND
  CH52  VDDCR_CPU1_CH52  POWER  = PVDDCR_CPU1_P1
  CH53  VDDCR_CPU1_CH53  POWER  = PVDDCR_CPU1_P1
  CH54  VSS_CH54  POWER  = GND
  CH55  MCB_DATA7  BI  = M_C_CPU1_SB_DQ<7>
  CH56  MCB_DATA8  BI  = M_C_CPU1_SB_DQ<8>
